# T6G (Grand Teton) — schematic netlist excerpt (pin names and nets, part order shuffled) for the footprints in the layout excerpt that follows; sources: Cadence DE-HDL packaged netlist, KiCad conversion of 04192023_DAF0TMB3IC0_F0TG_MB_C_brd_V02_OCP.brd

PC510_2  Q_CAP  0.1UF 25V 10% X7R  pkg 0402  page 225 : A = SW_P12V_AUX_PVDD11_S3_P1_FLT ; B = GND
D96  Q_LED  IC  pkg SMLF  page 254 : A = LED_PWRGD_PS_PWROK_PLD ; C = LED_PWRGD_PS_PWROK_PLD_D

(kicad_pcb
	(version 20260206)
	(generator "pcbnew")
	(generator_version "10.0")
	(general
		(thickness 1.6)
		(legacy_teardrops no)
	)
	(paper "A4")
	(title_block
		(title "04192023_DAF0TMB3IC0_F0TG_MB_C_brd_V02_OCP.brd")
		(comment 1 "Grand Teton / footprints 4923-4924 of 8354")
	)
	(layers
		(0 "F.Cu" signal "TOP")
		(4 "In1.Cu" signal "GND")
		(6 "In2.Cu" signal "IN1")
		(8 "In3.Cu" signal "GND1")
		(10 "In4.Cu" signal "IN2")
		(12 "In5.Cu" signal "GND2")
		(14 "In6.Cu" signal "IN3")
		(16 "In7.Cu" signal "GND3")
		(18 "In8.Cu" signal "VCC")
		(20 "In9.Cu" signal "VCC1")
		(22 "In10.Cu" signal "GND4")
		(24 "In11.Cu" signal "IN4")
		(26 "In12.Cu" signal "GND5")
		(28 "In13.Cu" signal "IN5")
		(30 "In14.Cu" signal "GND6")
		(32 "In15.Cu" signal "IN6")
		(34 "In16.Cu" signal "GND7")
		(2 "B.Cu" signal "BOTTOM")
		(9 "F.Adhes" user "F.Adhesive")
		(11 "B.Adhes" user "B.Adhesive")
		(13 "F.Paste" user "Package Geometry/Pastemask Top")
		(15 "B.Paste" user "Package Geometry/Pastemask Bottom")
		(5 "F.SilkS" user "Ref Des/Silkscreen Top")
		(7 "B.SilkS" user "Ref Des/Silkscreen Bottom")
		(1 "F.Mask" user "Board Geometry/Soldermask Top")
		(3 "B.Mask" user "Board Geometry/Soldermask Bottom")
		(17 "Dwgs.User" user "User.Drawings")
		(19 "Cmts.User" user "User.Comments")
		(21 "Eco1.User" user "User.Eco1")
		(23 "Eco2.User" user "User.Eco2")
		(25 "Edge.Cuts" user "Board Geometry/Outline")
		(27 "Margin" user)
		(31 "F.CrtYd" user "Package Geometry/Place Bound Top")
		(29 "B.CrtYd" user "Package Geometry/Place Bound Bottom")
		(35 "F.Fab" user "Ref Des/Assembly Top")
		(33 "B.Fab" user "Ref Des/Assembly Bottom")
	)
	(footprint ""
		(layer "F.Cu")
		(at 195.888864 -351.409254 -90)
		(property "Reference" "PC510_2"
			(at 0 0 270)
			(layer "F.SilkS")
			(hide yes)
			(effects
				(font
					(size 1.27 1.27)
				)
			)
		)
		(property "Value" ""
			(at 0 0 270)
			(layer "F.Fab")
			(effects
				(font
					(size 1.27 1.27)
				)
			)
		)
		(duplicate_pad_numbers_are_jumpers no)
		(fp_line
			(start -0.7874 0.4064)
			(end -0.7874 -0.4064)
			(stroke
				(width 0.1524)
				(type default)
			)
			(layer "F.SilkS")
		)
		(fp_line
			(start 0.7874 0.4064)
			(end -0.7874 0.4064)
			(stroke
				(width 0.1524)
				(type default)
			)
			(layer "F.SilkS")
		)
		(fp_line
			(start -0.7874 -0.4064)
			(end 0.7874 -0.4064)
			(stroke
				(width 0.1524)
				(type default)
			)
			(layer "F.SilkS")
		)
		(fp_line
			(start 0.7874 -0.4064)
			(end 0.7874 0.4064)
			(stroke
				(width 0.1524)
				(type default)
			)
			(layer "F.SilkS")
		)
		(fp_line
			(start -0.67945 0.3048)
			(end -0.67945 -0.305054)
			(stroke
				(width 0.1)
				(type default)
			)
			(layer "F.Fab")
		)
		(fp_line
			(start -0.12065 0.3048)
			(end -0.67945 0.3048)
			(stroke
				(width 0.1)
				(type default)
			)
			(layer "F.Fab")
		)
		(fp_line
			(start 0.120396 0.3048)
			(end 0.120396 0.2794)
			(stroke
				(width 0.1)
				(type default)
			)
			(layer "F.Fab")
		)
		(fp_line
			(start 0.67945 0.3048)
			(end 0.120396 0.3048)
			(stroke
				(width 0.1)
				(type default)
			)
			(layer "F.Fab")
		)
		(fp_line
			(start -0.12065 0.2794)
			(end -0.12065 0.3048)
			(stroke
				(width 0.1)
				(type default)
			)
			(layer "F.Fab")
		)
		(fp_line
			(start 0.120396 0.2794)
			(end -0.12065 0.2794)
			(stroke
				(width 0.1)
				(type default)
			)
			(layer "F.Fab")
		)
		(fp_line
			(start -0.12065 -0.2794)
			(end 0.12065 -0.2794)
			(stroke
				(width 0.1)
				(type default)
			)
			(layer "F.Fab")
		)
		(fp_line
			(start 0.12065 -0.2794)
			(end 0.12065 -0.3048)
			(stroke
				(width 0.1)
				(type default)
			)
			(layer "F.Fab")
		)
		(fp_line
			(start 0.12065 -0.3048)
			(end 0.67945 -0.3048)
			(stroke
				(width 0.1)
				(type default)
			)
			(layer "F.Fab")
		)
		(fp_line
			(start 0.67945 -0.3048)
			(end 0.67945 0.3048)
			(stroke
				(width 0.1)
				(type default)
			)
			(layer "F.Fab")
		)
		(fp_line
			(start -0.67945 -0.305054)
			(end -0.12065 -0.305054)
			(stroke
				(width 0.1)
				(type default)
			)
			(layer "F.Fab")
		)
		(fp_line
			(start -0.12065 -0.305054)
			(end -0.12065 -0.2794)
			(stroke
				(width 0.1)
				(type default)
			)
			(layer "F.Fab")
		)
		(pad "1" smd circle
			(at -0.40005 0 270)
			(size 0 0)
			(layers "F.Cu" "F.Mask" "F.Paste")
			(net "SW_P12V_AUX_PVDD11_S3_P1_FLT")
		)
		(pad "2" smd circle
			(at 0.40005 0 270)
			(size 0 0)
			(layers "F.Cu" "F.Mask" "F.Paste")
			(net "GND")
		)
	)
	(footprint ""
		(layer "F.Cu")
		(at 320.571876 -70.098412 90)
		(property "Reference" "D96"
			(at -3.934714 -0.691642 90)
			(unlocked yes)
			(layer "F.SilkS")
			(effects
				(font
					(size 0.7874 0.5842)
					(thickness 0.1524)
				)
				(justify left)
			)
		)
		(property "Value" ""
			(at 0 0 90)
			(layer "F.Fab")
			(effects
				(font
					(size 1.27 1.27)
				)
			)
		)
		(duplicate_pad_numbers_are_jumpers no)
		(fp_line
			(start 1.16078 -0.4826)
			(end 1.16078 0.4826)
			(stroke
				(width 0.1524)
				(type default)
			)
			(layer "F.SilkS")
		)
		(fp_line
			(start 1.03378 -0.4826)
			(end 1.03378 0.4826)
			(stroke
				(width 0.1524)
				(type default)
			)
			(layer "F.SilkS")
		)
		(fp_line
			(start 0.90678 -0.4826)
			(end 0.90678 0.4826)
			(stroke
				(width 0.1524)
				(type default)
			)
			(layer "F.SilkS")
		)
		(fp_line
			(start -0.64008 -0.4826)
			(end 1.16078 -0.4826)
			(stroke
				(width 0.1524)
				(type default)
			)
			(layer "F.SilkS")
		)
		(fp_line
			(start -0.79248 -0.4826)
			(end 1.03378 -0.4826)
			(stroke
				(width 0.1524)
				(type default)
			)
			(layer "F.SilkS")
		)
		(fp_line
			(start -0.89408 -0.4826)
			(end 0.90678 -0.4826)
			(stroke
				(width 0.1524)
				(type default)
			)
			(layer "F.SilkS")
		)
		(fp_line
			(start 1.16078 0.4826)
			(end -0.64008 0.4826)
			(stroke
				(width 0.1524)
				(type default)
			)
			(layer "F.SilkS")
		)
		(fp_line
			(start 1.03378 0.4826)
			(end -0.79248 0.4826)
			(stroke
				(width 0.1524)
				(type default)
			)
			(layer "F.SilkS")
		)
		(fp_line
			(start 0.90678 0.4826)
			(end -0.90678 0.4826)
			(stroke
				(width 0.1524)
				(type default)
			)
			(layer "F.SilkS")
		)
		(fp_line
			(start -0.90678 0.4826)
			(end -0.90678 -0.4699)
			(stroke
				(width 0.1524)
				(type default)
			)
			(layer "F.SilkS")
		)
		(fp_line
			(start 0.499872 -0.249936)
			(end 0.499872 0.249936)
			(stroke
				(width 0.1)
				(type default)
			)
			(layer "F.Fab")
		)
		(fp_line
			(start -0.499872 -0.249936)
			(end 0.499872 -0.249936)
			(stroke
				(width 0.1)
				(type default)
			)
			(layer "F.Fab")
		)
		(fp_line
			(start 0.499872 0.249936)
			(end -0.499872 0.249936)
			(stroke
				(width 0.1)
				(type default)
			)
			(layer "F.Fab")
		)
		(fp_line
			(start -0.499872 0.249936)
			(end -0.499872 -0.249936)
			(stroke
				(width 0.1)
				(type default)
			)
			(layer "F.Fab")
		)
		(pad "A" smd rect
			(at -0.47498 0 90)
			(size 0.6096 0.7112)
			(layers "F.Cu" "F.Mask" "F.Paste")
			(net "LED_PWRGD_PS_PWROK_PLD")
		)
		(pad "C" smd rect
			(at 0.47498 0 90)
			(size 0.6096 0.7112)
			(layers "F.Cu" "F.Mask" "F.Paste")
			(net "LED_PWRGD_PS_PWROK_PLD_D")
		)
	)
)
